# T6G (Grand Teton) — schematic netlist excerpt (pin names and nets, part order shuffled) for the footprints in the layout excerpt that follows; sources: Cadence DE-HDL packaged netlist, KiCad conversion of 04192023_DAF0TMB3IC0_F0TG_MB_C_brd_V02_OCP.brd

J99  SCONN288_DDR506112002KQ  IO  pkg DDR288S_1-1VXC  page 108
  VIN_BULK0  = P12V_MEM_CPU1
  RFU0  = NC
  VIN_MGMT  = P3V3_AUX
  HSCL  = I3C_SPD_DDRK_CPU1_SCL
  HSDA  = I3C_SPD_DDRK_CPU1_SDA
  VSS0  = GND
  DQ0_A  = M_K_CPU1_SA_DQ<0>
  VSS1  = GND
  DQ1_A  = M_K_CPU1_SA_DQ<1>
  VSS2  = GND
  DQS0_A_T  = M_K_CPU1_SA_DQS_DP<0>
  DQS0_A_C  = M_K_CPU1_SA_DQS_DN<0>
  VSS3  = GND
  DQ4_A  = M_K_CPU1_SA_DQ<4>
  VSS4  = GND
  DQ5_A  = M_K_CPU1_SA_DQ<5>
  VSS5  = GND
  DQ8_A  = M_K_CPU1_SA_DQ<8>
  VSS6  = GND
  DQ9_A  = M_K_CPU1_SA_DQ<9>
  VSS7  = GND
  DQS1_A_T  = M_K_CPU1_SA_DQS_DP<1>
  DQS1_A_C  = M_K_CPU1_SA_DQS_DN<1>
  VSS8  = GND
  DQ12_A  = M_K_CPU1_SA_DQ<12>
  VSS9  = GND
  DQ13_A  = M_K_CPU1_SA_DQ<13>
  VSS10  = GND
  DQ16_A  = M_K_CPU1_SA_DQ<16>
  VSS11  = GND
  DQ17_A  = M_K_CPU1_SA_DQ<17>
  VSS12  = GND
  DQS2_A_T  = M_K_CPU1_SA_DQS_DP<2>
  DQS2_A_C  = M_K_CPU1_SA_DQS_DN<2>
  VSS13  = GND
  DQ20_A  = M_K_CPU1_SA_DQ<20>
  VSS14  = GND
  DQ21_A  = M_K_CPU1_SA_DQ<21>
  VSS15  = GND
  DQ24_A  = M_K_CPU1_SA_DQ<24>
  VSS16  = GND
  DQ25_A  = M_K_CPU1_SA_DQ<25>
  VSS17  = GND
  DQS3_A_T  = M_K_CPU1_SA_DQS_DP<3>
  DQS3_A_C  = M_K_CPU1_SA_DQS_DN<3>
  VSS18  = GND
  DQ28_A  = M_K_CPU1_SA_DQ<28>
  VSS19  = GND
  DQ29_A  = M_K_CPU1_SA_DQ<29>
  VSS20  = GND
  CB0_A  = M_K_CPU1_SA_CB<0>
  VSS21  = GND
  CB1_A  = M_K_CPU1_SA_CB<1>
  VSS22  = GND
  DQS4_A_T  = M_K_CPU1_SA_DQS_DP<4>
  DQS4_A_C  = M_K_CPU1_SA_DQS_DN<4>
  VSS23  = GND
  CB4_A  = M_K_CPU1_SA_CB<4>
  VSS24  = GND
  CB5_A  = M_K_CPU1_SA_CB<5>
  VSS25  = GND
  ALERT_N  = M_K_CPU1_ALERT_N
  VSS26  = GND
  CS0_A_N  = M_K_CPU1_SA_CS_N<0>
  VSS27  = GND
  CA0_A  = M_K_CPU1_SA_CA<0>
  VSS28  = GND
  CA2_A  = M_K_CPU1_SA_CA<2>
  VSS29  = GND
  CA4_A  = M_K_CPU1_SA_CA<4>
  VSS30  = GND
  CA6_A  = M_K_CPU1_SA_CA<6>
  VSS31  = GND
  PAR_A  = M_K_CPU1_SA_PAR
  VSS32  = GND
  CA0_B  = M_K_CPU1_SB_CA<0>
  VSS33  = GND
  CA2_B  = M_K_CPU1_SB_CA<2>
  VSS34  = GND
  CA4_B  = M_K_CPU1_SB_CA<4>
  VSS35  = GND
  CA6_B  = M_K_CPU1_SB_CA<6>
  VSS36  = GND
  CS0_B_N  = M_K_CPU1_SB_CS_N<0>
  VSS37  = GND
  \lbd||rsp_a_n\  = M_K_CPU1_SA_RSP<0>
  \lbs||rsp_b_n\  = M_K_CPU1_SB_RSP<0>
  VSS38  = GND
  CB4_B  = M_K_CPU1_SB_CB<4>
  VSS39  = GND
  CB5_B  = M_K_CPU1_SB_CB<5>
  VSS40  = GND
  \dqs9_b_t||tdqs9_b_t||dbi4_b_n\  = M_K_CPU1_SB_DQS_DP<9>
  \dqs9_b_c||tdqs9_b_c\  = M_K_CPU1_SB_DQS_DN<9>
  VSS41  = GND
  CB0_B  = M_K_CPU1_SB_CB<0>
  VSS42  = GND
  CB1_B  = M_K_CPU1_SB_CB<1>
  VSS43  = GND
  DQ0_B  = M_K_CPU1_SB_DQ<0>
  VSS44  = GND
  DQ1_B  = M_K_CPU1_SB_DQ<1>
  VSS45  = GND
  DQS0_B_T  = M_K_CPU1_SB_DQS_DP<0>
  DQS0_B_C  = M_K_CPU1_SB_DQS_DN<0>
  VSS46  = GND
  DQ4_B  = M_K_CPU1_SB_DQ<4>
  VSS47  = GND
  DQ5_B  = M_K_CPU1_SB_DQ<5>
  VSS48  = GND
  DQ8_B  = M_K_CPU1_SB_DQ<8>
  VSS49  = GND
  DQ9_B  = M_K_CPU1_SB_DQ<9>
  VSS50  = GND
  DQS1_B_T  = M_K_CPU1_SB_DQS_DP<1>
  DQS1_B_C  = M_K_CPU1_SB_DQS_DN<1>
  VSS51  = GND
  DQ12_B  = M_K_CPU1_SB_DQ<12>
  VSS52  = GND
  DQ13_B  = M_K_CPU1_SB_DQ<13>
  VSS53  = GND
  DQ16_B  = M_K_CPU1_SB_DQ<16>
  VSS54  = GND
  DQ17_B  = M_K_CPU1_SB_DQ<17>
  VSS55  = GND
  DQS2_B_T  = M_K_CPU1_SB_DQS_DP<2>
  DQS2_B_C  = M_K_CPU1_SB_DQS_DN<2>
  VSS56  = GND
  DQ20_B  = M_K_CPU1_SB_DQ<20>
  VSS57  = GND
  DQ21_B  = M_K_CPU1_SB_DQ<21>
  VSS58  = GND
  DQ24_B  = M_K_CPU1_SB_DQ<24>
  VSS59  = GND
  DQ25_B  = M_K_CPU1_SB_DQ<25>
  VSS60  = GND
  DQS3_B_T  = M_K_CPU1_SB_DQS_DP<3>
  DQS3_B_C  = M_K_CPU1_SB_DQS_DN<3>
  VSS61  = GND
  DQ28_B  = M_K_CPU1_SB_DQ<28>
  VSS62  = GND
  DQ29_B  = M_K_CPU1_SB_DQ<29>
  VSS63  = GND
  RFU1  = NC
  VIN_BULK1  = P12V_MEM_CPU1
  VIN_BULK2  = P12V_MEM_CPU1
  \pwr_good||fail_n\  = PWRGD_CHK_CPU1_DIMM
  HAS  = PD_CHK_CPU1_DIMM_SAA
  RFU2  = NC
  RFU3  = NC
  VSS64  = GND
  DQ2_A  = M_K_CPU1_SA_DQ<2>
  VSS65  = GND
  DQ3_A  = M_K_CPU1_SA_DQ<3>
  VSS66  = GND
  \dqs5_a_c||tdqs5_a_c||dqs5_a_t||tdqs5_a_t\  = M_K_CPU1_SA_DQS_DN<5>
  \dqs5_a_t||tdqs5_a_t\  = M_K_CPU1_SA_DQS_DP<5>
  VSS67  = GND
  DQ6_A  = M_K_CPU1_SA_DQ<6>
  VSS68  = GND
  DQ7_A  = M_K_CPU1_SA_DQ<7>
  VSS69  = GND
  DQ10_A  = M_K_CPU1_SA_DQ<10>
  VSS70  = GND
  DQ11_A  = M_K_CPU1_SA_DQ<11>
  VSS71  = GND
  \dqs6_a_c||tdqs6_a_c||dqs6_a_t||tdqs6_a_t\  = M_K_CPU1_SA_DQS_DN<6>
  \dqs6_a_t||tdqs6_a_t\  = M_K_CPU1_SA_DQS_DP<6>
  VSS72  = GND
  DQ14_A  = M_K_CPU1_SA_DQ<14>
  VSS73  = GND
  DQ15_A  = M_K_CPU1_SA_DQ<15>
  VSS74  = GND
  DQ18_A  = M_K_CPU1_SA_DQ<18>
  VSS75  = GND
  DQ19_A  = M_K_CPU1_SA_DQ<19>
  VSS76  = GND
  \dqs7_a_c||tdqs7_a_c\  = M_K_CPU1_SA_DQS_DN<7>
  \dqs7_a_t||tdqs7_a_t\  = M_K_CPU1_SA_DQS_DP<7>
  VSS77  = GND
  DQ22_A  = M_K_CPU1_SA_DQ<22>
  VSS78  = GND
  DQ23_A  = M_K_CPU1_SA_DQ<23>
  VSS79  = GND
  DQ26_A  = M_K_CPU1_SA_DQ<26>
  VSS80  = GND
  DQ27_A  = M_K_CPU1_SA_DQ<27>
  VSS81  = GND
  \dqs8_a_c||tdqs8_a_c\  = M_K_CPU1_SA_DQS_DN<8>
  \dqs8_a_t||tdqs8_a_t\  = M_K_CPU1_SA_DQS_DP<8>
  VSS82  = GND
  DQ30_A  = M_K_CPU1_SA_DQ<30>
  VSS83  = GND
  DQ31_A  = M_K_CPU1_SA_DQ<31>
  VSS84  = GND
  CB2_A  = M_K_CPU1_SA_CB<2>
  VSS85  = GND
  CB3_A  = M_K_CPU1_SA_CB<3>
  VSS86  = GND
  \dqs9_a_c||tdqs9_a_c\  = M_K_CPU1_SA_DQS_DN<9>
  \dqs9_a_t||tdqs9_a_t\  = M_K_CPU1_SA_DQS_DP<9>
  VSS87  = GND
  CB6_A  = M_K_CPU1_SA_CB<6>
  VSS88  = GND
  CB7_A  = M_K_CPU1_SA_CB<7>
  VSS89  = GND
  RESET_N  = M_K_CPU1_RESET_N
  VSS90  = GND
  CS1_A_N  = M_K_CPU1_SA_CS_N<1>
  VSS91  = GND
  CA1_A  = M_K_CPU1_SA_CA<1>
  VSS92  = GND
  CA3_A  = M_K_CPU1_SA_CA<3>
  VSS93  = GND
  CA5_A  = M_K_CPU1_SA_CA<5>
  VSS94  = GND
  CK_T  = M_K_CPU1_CLK_DP<0>
  CK_C  = M_K_CPU1_CLK_DN<0>
  VSS95  = GND
  RFU4  = NC
  CA1_B  = M_K_CPU1_SB_CA<1>
  VSS96  = GND
  CA3_B  = M_K_CPU1_SB_CA<3>
  VSS97  = GND
  CA5_B  = M_K_CPU1_SB_CA<5>
  VSS98  = GND
  PAR_B  = M_K_CPU1_SB_PAR
  VSS99  = GND
  CS1_B_N  = M_K_CPU1_SB_CS_N<1>
  VSS100  = GND
  RFU5  = NC
  RFU6  = NC
  VSS101  = GND
  CB6_B  = M_K_CPU1_SB_CB<6>
  VSS102  = GND
  CB7_B  = M_K_CPU1_SB_CB<7>
  VSS103  = GND
  DQS4_B_C  = M_K_CPU1_SB_DQS_DN<4>
  DQS4_B_T  = M_K_CPU1_SB_DQS_DP<4>
  VSS104  = GND
  CB2_B  = M_K_CPU1_SB_CB<2>
  VSS105  = GND
  CB3_B  = M_K_CPU1_SB_CB<3>
  VSS106  = GND
  DQ2_B  = M_K_CPU1_SB_DQ<2>
  VSS107  = GND
  DQ3_B  = M_K_CPU1_SB_DQ<3>
  VSS108  = GND
  \dqs5_b_c||tdqs5_b_c\  = M_K_CPU1_SB_DQS_DN<5>
  \dqs5_b_t||tdqs5_b_t\  = M_K_CPU1_SB_DQS_DP<5>
  VSS109  = GND
  DQ6_B  = M_K_CPU1_SB_DQ<6>
  VSS110  = GND
  DQ7_B  = M_K_CPU1_SB_DQ<7>
  VSS111  = GND
  DQ10_B  = M_K_CPU1_SB_DQ<10>
  VSS112  = GND
  DQ11_B  = M_K_CPU1_SB_DQ<11>
  VSS113  = GND
  \dqs6_b_c||tdqs6_b_c\  = M_K_CPU1_SB_DQS_DN<6>
  \dqs6_b_t||tdqs6_b_t\  = M_K_CPU1_SB_DQS_DP<6>
  VSS114  = GND
  DQ14_B  = M_K_CPU1_SB_DQ<14>
  VSS115  = GND
  DQ15_B  = M_K_CPU1_SB_DQ<15>
  VSS116  = GND
  DQ18_B  = M_K_CPU1_SB_DQ<18>
  VSS117  = GND
  DQ19_B  = M_K_CPU1_SB_DQ<19>
  VSS118  = GND
  \dqs7_b_c||tdqs7_b_c\  = M_K_CPU1_SB_DQS_DN<7>
  \dqs7_b_t||tdqs7_b_t\  = M_K_CPU1_SB_DQS_DP<7>
  VSS119  = GND
  DQ22_B  = M_K_CPU1_SB_DQ<22>
  VSS120  = GND
  DQ23_B  = M_K_CPU1_SB_DQ<23>
  VSS121  = GND
  DQ26_B  = M_K_CPU1_SB_DQ<26>
  VSS122  = GND
  DQ27_B  = M_K_CPU1_SB_DQ<27>
  VSS123  = GND
  \dqs8_b_c||tdqs8_b_c\  = M_K_CPU1_SB_DQS_DN<8>
  \dqs8_b_t||tdqs8_b_t\  = M_K_CPU1_SB_DQS_DP<8>
  VSS124  = GND
  DQ30_B  = M_K_CPU1_SB_DQ<30>
  VSS125  = GND
  DQ31_B  = M_K_CPU1_SB_DQ<31>
  VSS126  = GND
  G1  = GND
  G2  = GND
  G3  = GND

(kicad_pcb
	(version 20260206)
	(generator "pcbnew")
	(generator_version "10.0")
	(general
		(thickness 1.6)
		(legacy_teardrops no)
	)
	(paper "A4")
	(title_block
		(title "04192023_DAF0TMB3IC0_F0TG_MB_C_brd_V02_OCP.brd")
		(comment 1 "Grand Teton / footprint 4555 of 8354 (J99), pads 277-291 of 291")
	)
	(layers
		(0 "F.Cu" signal "TOP")
		(4 "In1.Cu" signal "GND")
		(6 "In2.Cu" signal "IN1")
		(8 "In3.Cu" signal "GND1")
		(10 "In4.Cu" signal "IN2")
		(12 "In5.Cu" signal "GND2")
		(14 "In6.Cu" signal "IN3")
		(16 "In7.Cu" signal "GND3")
		(18 "In8.Cu" signal "VCC")
		(20 "In9.Cu" signal "VCC1")
		(22 "In10.Cu" signal "GND4")
		(24 "In11.Cu" signal "IN4")
		(26 "In12.Cu" signal "GND5")
		(28 "In13.Cu" signal "IN5")
		(30 "In14.Cu" signal "GND6")
		(32 "In15.Cu" signal "IN6")
		(34 "In16.Cu" signal "GND7")
		(2 "B.Cu" signal "BOTTOM")
		(9 "F.Adhes" user "F.Adhesive")
		(11 "B.Adhes" user "B.Adhesive")
		(13 "F.Paste" user "Package Geometry/Pastemask Top")
		(15 "B.Paste" user "Package Geometry/Pastemask Bottom")
		(5 "F.SilkS" user "Ref Des/Silkscreen Top")
		(7 "B.SilkS" user "Ref Des/Silkscreen Bottom")
		(1 "F.Mask" user "Board Geometry/Soldermask Top")
		(3 "B.Mask" user "Board Geometry/Soldermask Bottom")
		(17 "Dwgs.User" user "User.Drawings")
		(19 "Cmts.User" user "User.Comments")
		(21 "Eco1.User" user "User.Eco1")
		(23 "Eco2.User" user "User.Eco2")
		(25 "Edge.Cuts" user "Board Geometry/Outline")
		(27 "Margin" user)
		(31 "F.CrtYd" user "Package Geometry/Place Bound Top")
		(29 "B.CrtYd" user "Package Geometry/Place Bound Bottom")
		(35 "F.Fab" user "Ref Des/Assembly Top")
		(33 "B.Fab" user "Ref Des/Assembly Bottom")
	)
	(footprint ""
		(layer "F.Cu")
		(at 196.654166 -255.560322 180)
		(property "Reference" "J99"
			(at -0.4318 -81.730088 0)
			(unlocked yes)
			(layer "F.SilkS")
			(effects
				(font
					(size 0.7874 0.5842)
					(thickness 0.1524)
				)
			)
		)
		(property "Value" ""
			(at 0 0 180)
			(layer "F.Fab")
			(effects
				(font
					(size 1.27 1.27)
				)
			)
		)
		(duplicate_pad_numbers_are_jumpers no)
		(pad "277" smd rect
			(at 2.050034 53.975 90)
			(size 0.519938 1.4986)
			(layers "F.Cu" "F.Mask" "F.Paste")
			(net "GND")
		)
		(pad "278" smd rect
			(at 2.050034 54.824884 90)
			(size 0.519938 1.4986)
			(layers "F.Cu" "F.Mask" "F.Paste")
			(net "M_K_CPU1_SB_DQ<26>")
		)
		(pad "279" smd rect
			(at 2.050034 55.675022 90)
			(size 0.519938 1.4986)
			(layers "F.Cu" "F.Mask" "F.Paste")
			(net "GND")
		)
		(pad "280" smd rect
			(at 2.050034 56.524906 90)
			(size 0.519938 1.4986)
			(layers "F.Cu" "F.Mask" "F.Paste")
			(net "M_K_CPU1_SB_DQ<27>")
		)
		(pad "281" smd rect
			(at 2.050034 57.375044 90)
			(size 0.519938 1.4986)
			(layers "F.Cu" "F.Mask" "F.Paste")
			(net "GND")
		)
		(pad "282" smd rect
			(at 2.050034 58.224928 90)
			(size 0.519938 1.4986)
			(layers "F.Cu" "F.Mask" "F.Paste")
			(net "M_K_CPU1_SB_DQS_DN<8>")
		)
		(pad "283" smd rect
			(at 2.050034 59.075066 90)
			(size 0.519938 1.4986)
			(layers "F.Cu" "F.Mask" "F.Paste")
			(net "M_K_CPU1_SB_DQS_DP<8>")
		)
		(pad "284" smd rect
			(at 2.050034 59.92495 90)
			(size 0.519938 1.4986)
			(layers "F.Cu" "F.Mask" "F.Paste")
			(net "GND")
		)
		(pad "285" smd rect
			(at 2.050034 60.775088 90)
			(size 0.519938 1.4986)
			(layers "F.Cu" "F.Mask" "F.Paste")
			(net "M_K_CPU1_SB_DQ<30>")
		)
		(pad "286" smd rect
			(at 2.050034 61.624972 90)
			(size 0.519938 1.4986)
			(layers "F.Cu" "F.Mask" "F.Paste")
			(net "GND")
		)
		(pad "287" smd rect
			(at 2.050034 62.47511 90)
			(size 0.519938 1.4986)
			(layers "F.Cu" "F.Mask" "F.Paste")
			(net "M_K_CPU1_SB_DQ<31>")
		)
		(pad "288" smd rect
			(at 2.050034 63.324994 90)
			(size 0.519938 1.4986)
			(layers "F.Cu" "F.Mask" "F.Paste")
			(net "GND")
		)
		(pad "G1" thru_hole oval
			(at 0 -68.97497 90)
			(size 1.7272 3.4798)
			(drill oval 1.2192 2.4638)
			(layers "*.Cu" "*.Mask")
			(remove_unused_layers no)
			(net "GND")
			(clearance 0.127)
			(thermal_gap 0.127)
		)
		(pad "G2" thru_hole oval
			(at 0 3.875024 90)
			(size 1.7272 3.4798)
			(drill oval 1.2192 2.4638)
			(layers "*.Cu" "*.Mask")
			(remove_unused_layers no)
			(net "GND")
			(clearance 0.127)
			(thermal_gap 0.127)
		)
		(pad "G3" thru_hole oval
			(at 0 68.97497 90)
			(size 1.7272 3.4798)
			(drill oval 1.2192 2.4638)
			(layers "*.Cu" "*.Mask")
			(remove_unused_layers no)
			(net "GND")
			(clearance 0.127)
			(thermal_gap 0.127)
		)
	)
)
